FILE_TYPE = MACRO_DRAWING;
SET COLOR_WIRE YELLOW;
SET COLOR_PROP ORANGE;
SET COLOR_DOT WHITE;
SET COLOR_ARC YELLOW;
SET COLOR_BODY GREEN;
SET COLOR_NOTE PURPLE;
SET PROP_DISPLAY VALUE;
SET PAGE_NUMBER P205;
FORCEADD QUANTA_TITLE_BLOCK_C..1
(4700 -1775);
FORCEPROP 1 LAST CUSTOM_TXT_CDS <NAME_2>
J 0
(1525 -1725);
FORCEPROP 1 LAST CUSTOM_TXT_CDS <NAME_1>
J 0
(1525 -1600);
FORCEPROP 1 LAST CUSTOM_TXT_CDS <Q_NUMBER>
J 0
(3297 -1672);
DISPLAY 1.212766 (3297 -1672);
FORCEPROP 1 LAST CUSTOM_TXT_CDS <Q_PROJ>
J 0
(2318 -1673);
DISPLAY 1.212766 (2318 -1673);
FORCEPROP 1 LAST CUSTOM_TXT_CDS <Q_REV>
J 0
(4516 -1672);
DISPLAY 1.212766 (4516 -1672);
FORCEPROP 1 LAST CUSTOM_TXT_CDS <CON_LAST_MODIFIED>
J 0
(2815 -1760);
DISPLAY 0.978723 (2815 -1760);
FORCEPROP 1 LAST CUSTOM_TXT_CDS <CON_PAGE_NUM> OF <CON_TOTAL_PAGES>
J 0
(4254 -1757);
DISPLAY 0.978723 (4254 -1757);
FORCEPROP 1 LAST Q_DEPT BU9
J 1
(937 -1726);
DISPLAY 1.957447 (937 -1726);
PAINT GREEN (937 -1726);
FORCEPROP 1 LAST Q_TITLE eFUSE - E1S_2
J 0
(-4600 -1725);
DISPLAY 2.446809 (-4600 -1725);
PAINT GREEN (-4600 -1725);
FORCEPROP 1 LAST CDS_LMAN_SYM_OUTLINE -9475,6775,100,-125
J 0
(4700 -1775);
DISPLAY 0.468085 (4700 -1775);
PAINT GREEN (4700 -1775);
DISPLAY INVISIBLE (4700 -1775);
FORCEPROP 2 LAST CDS_LIB pure_quanta
J 0
(4700 -1775);
DISPLAY INVISIBLE (4700 -1775);
FORCEPROP 2 LAST PAGE_BORDER TRUE
J 0
(-3190 3475);
DISPLAY 0.638298 (-3190 3475);
PAINT PINK (-3190 3475);
DISPLAY INVISIBLE (-3190 3475);
FORCEPROP 1 LAST COMMENT_BODY TRUE
J 0
(4712 -1788);
DISPLAY 0.978723 (4712 -1788);
PAINT GREEN (4712 -1788);
DISPLAY INVISIBLE (4712 -1788);
FORCEPROP 2 LAST CDS_XR_PAGE_TITLE CR-206 : @T6G_MB_LIB.T6G(SCH_1):PAGE206
J 0
(-3190 3475);
DISPLAY 0.638298 (-3190 3475);
PAINT PINK (-3190 3475);
DISPLAY INVISIBLE (-3190 3475);
FORCEPROP 2 LAST CUSTOM_TXT_CDS <XR_PAGE_TITLE>
J 0
(-3190 3475);
DISPLAY 0.638298 (-3190 3475);
PAINT PINK (-3190 3475);
DISPLAY INVISIBLE (-3190 3475);
FORCEPROP 0 LAST CDS_CON_LAST_MODIFIED Wed Mar 09 21:44:33 2022
J 0
(2815 -1760);
DISPLAY INVISIBLE (2815 -1760);
QUIT
